# S9S_MB_2U (Grand Teton) — schematic netlist excerpt (pin names and nets, part order shuffled) for the footprints in the layout excerpt that follows; sources: Cadence DE-HDL packaged netlist, KiCad conversion of 03242023_DA0F0TMBIJ0_F0T_Motherboard_J_brd_V01_OCP.brd

C2045  Q_CAP  100PF 50V 5% EMPTY  pkg 0402  page 250 : A = P3V3_PDB_AUX_ADC_MAM ; B = GND
R3643  Q_RES  10K 1% CHIP  pkg 0402LF  page 208 : A = P3V3_AUX ; B = CK440Q_OE_6

(kicad_pcb
	(version 20260206)
	(generator "pcbnew")
	(generator_version "10.0")
	(general
		(thickness 1.6)
		(legacy_teardrops no)
	)
	(paper "A4")
	(title_block
		(title "03242023_DA0F0TMBIJ0_F0T_Motherboard_J_brd_V01_OCP.brd")
		(comment 1 "Grand Teton / footprints 1546-1547 of 6105")
	)
	(layers
		(0 "F.Cu" signal "TOP")
		(4 "In1.Cu" signal "GND")
		(6 "In2.Cu" signal "IN1")
		(8 "In3.Cu" signal "GND1")
		(10 "In4.Cu" signal "IN2")
		(12 "In5.Cu" signal "GND2")
		(14 "In6.Cu" signal "IN3")
		(16 "In7.Cu" signal "GND3")
		(18 "In8.Cu" signal "VCC")
		(20 "In9.Cu" signal "VCC1")
		(22 "In10.Cu" signal "GND4")
		(24 "In11.Cu" signal "IN4")
		(26 "In12.Cu" signal "GND5")
		(28 "In13.Cu" signal "IN5")
		(30 "In14.Cu" signal "GND6")
		(32 "In15.Cu" signal "IN6")
		(34 "In16.Cu" signal "GND7")
		(2 "B.Cu" signal "BOTTOM")
		(9 "F.Adhes" user "F.Adhesive")
		(11 "B.Adhes" user "B.Adhesive")
		(13 "F.Paste" user "Package Geometry/Pastemask Top")
		(15 "B.Paste" user "Package Geometry/Pastemask Bottom")
		(5 "F.SilkS" user "Ref Des/Silkscreen Top")
		(7 "B.SilkS" user "Ref Des/Silkscreen Bottom")
		(1 "F.Mask" user "Board Geometry/Soldermask Top")
		(3 "B.Mask" user "Board Geometry/Soldermask Bottom")
		(17 "Dwgs.User" user "User.Drawings")
		(19 "Cmts.User" user "User.Comments")
		(21 "Eco1.User" user "User.Eco1")
		(23 "Eco2.User" user "User.Eco2")
		(25 "Edge.Cuts" user "Board Geometry/Outline")
		(27 "Margin" user)
		(31 "F.CrtYd" user "Package Geometry/Place Bound Top")
		(29 "B.CrtYd" user "Package Geometry/Place Bound Bottom")
		(35 "F.Fab" user "Ref Des/Assembly Top")
		(33 "B.Fab" user "Ref Des/Assembly Bottom")
	)
	(footprint ""
		(layer "F.Cu")
		(at 254.58674 -92.291408 180)
		(property "Reference" "R3643"
			(at 0 0 180)
			(layer "F.SilkS")
			(hide yes)
			(effects
				(font
					(size 1.27 1.27)
				)
			)
		)
		(property "Value" ""
			(at 0 0 180)
			(layer "F.Fab")
			(effects
				(font
					(size 1.27 1.27)
				)
			)
		)
		(duplicate_pad_numbers_are_jumpers no)
		(fp_line
			(start 0.7874 0.4064)
			(end -0.7874 0.4064)
			(stroke
				(width 0.1524)
				(type default)
			)
			(layer "F.SilkS")
		)
		(fp_line
			(start 0.7874 -0.4064)
			(end 0.7874 0.4064)
			(stroke
				(width 0.1524)
				(type default)
			)
			(layer "F.SilkS")
		)
		(fp_line
			(start -0.7874 0.4064)
			(end -0.7874 -0.4064)
			(stroke
				(width 0.1524)
				(type default)
			)
			(layer "F.SilkS")
		)
		(fp_line
			(start -0.7874 -0.4064)
			(end 0.7874 -0.4064)
			(stroke
				(width 0.1524)
				(type default)
			)
			(layer "F.SilkS")
		)
		(fp_line
			(start 0.67945 0.3048)
			(end 0.120396 0.3048)
			(stroke
				(width 0.1)
				(type default)
			)
			(layer "F.Fab")
		)
		(fp_line
			(start 0.67945 -0.3048)
			(end 0.67945 0.3048)
			(stroke
				(width 0.1)
				(type default)
			)
			(layer "F.Fab")
		)
		(fp_line
			(start 0.12065 -0.2794)
			(end 0.12065 -0.3048)
			(stroke
				(width 0.1)
				(type default)
			)
			(layer "F.Fab")
		)
		(fp_line
			(start 0.12065 -0.3048)
			(end 0.67945 -0.3048)
			(stroke
				(width 0.1)
				(type default)
			)
			(layer "F.Fab")
		)
		(fp_line
			(start 0.120396 0.3048)
			(end 0.120396 0.2794)
			(stroke
				(width 0.1)
				(type default)
			)
			(layer "F.Fab")
		)
		(fp_line
			(start 0.120396 0.2794)
			(end -0.12065 0.2794)
			(stroke
				(width 0.1)
				(type default)
			)
			(layer "F.Fab")
		)
		(fp_line
			(start -0.12065 0.3048)
			(end -0.67945 0.3048)
			(stroke
				(width 0.1)
				(type default)
			)
			(layer "F.Fab")
		)
		(fp_line
			(start -0.12065 0.2794)
			(end -0.12065 0.3048)
			(stroke
				(width 0.1)
				(type default)
			)
			(layer "F.Fab")
		)
		(fp_line
			(start -0.12065 -0.2794)
			(end 0.12065 -0.2794)
			(stroke
				(width 0.1)
				(type default)
			)
			(layer "F.Fab")
		)
		(fp_line
			(start -0.12065 -0.305054)
			(end -0.12065 -0.2794)
			(stroke
				(width 0.1)
				(type default)
			)
			(layer "F.Fab")
		)
		(fp_line
			(start -0.67945 0.3048)
			(end -0.67945 -0.305054)
			(stroke
				(width 0.1)
				(type default)
			)
			(layer "F.Fab")
		)
		(fp_line
			(start -0.67945 -0.305054)
			(end -0.12065 -0.305054)
			(stroke
				(width 0.1)
				(type default)
			)
			(layer "F.Fab")
		)
		(pad "1" smd circle
			(at -0.40005 0 180)
			(size 0 0)
			(layers "F.Cu" "F.Mask" "F.Paste")
			(net "P3V3_AUX")
		)
		(pad "2" smd circle
			(at 0.40005 0 180)
			(size 0 0)
			(layers "F.Cu" "F.Mask" "F.Paste")
			(net "CK440Q_OE_6")
		)
	)
	(footprint ""
		(layer "F.Cu")
		(at 46.350428 -99.840034)
		(property "Reference" "C2045"
			(at 0 0 0)
			(layer "F.SilkS")
			(hide yes)
			(effects
				(font
					(size 1.27 1.27)
				)
			)
		)
		(property "Value" ""
			(at 0 0 0)
			(layer "F.Fab")
			(effects
				(font
					(size 1.27 1.27)
				)
			)
		)
		(duplicate_pad_numbers_are_jumpers no)
		(fp_line
			(start -0.7874 -0.4064)
			(end 0.7874 -0.4064)
			(stroke
				(width 0.1524)
				(type default)
			)
			(layer "F.SilkS")
		)
		(fp_line
			(start -0.7874 0.4064)
			(end -0.7874 -0.4064)
			(stroke
				(width 0.1524)
				(type default)
			)
			(layer "F.SilkS")
		)
		(fp_line
			(start 0.7874 -0.4064)
			(end 0.7874 0.4064)
			(stroke
				(width 0.1524)
				(type default)
			)
			(layer "F.SilkS")
		)
		(fp_line
			(start 0.7874 0.4064)
			(end -0.7874 0.4064)
			(stroke
				(width 0.1524)
				(type default)
			)
			(layer "F.SilkS")
		)
		(fp_line
			(start -0.67945 -0.305054)
			(end -0.12065 -0.305054)
			(stroke
				(width 0.1)
				(type default)
			)
			(layer "F.Fab")
		)
		(fp_line
			(start -0.67945 0.3048)
			(end -0.67945 -0.305054)
			(stroke
				(width 0.1)
				(type default)
			)
			(layer "F.Fab")
		)
		(fp_line
			(start -0.12065 -0.305054)
			(end -0.12065 -0.2794)
			(stroke
				(width 0.1)
				(type default)
			)
			(layer "F.Fab")
		)
		(fp_line
			(start -0.12065 -0.2794)
			(end 0.12065 -0.2794)
			(stroke
				(width 0.1)
				(type default)
			)
			(layer "F.Fab")
		)
		(fp_line
			(start -0.12065 0.2794)
			(end -0.12065 0.3048)
			(stroke
				(width 0.1)
				(type default)
			)
			(layer "F.Fab")
		)
		(fp_line
			(start -0.12065 0.3048)
			(end -0.67945 0.3048)
			(stroke
				(width 0.1)
				(type default)
			)
			(layer "F.Fab")
		)
		(fp_line
			(start 0.120396 0.2794)
			(end -0.12065 0.2794)
			(stroke
				(width 0.1)
				(type default)
			)
			(layer "F.Fab")
		)
		(fp_line
			(start 0.120396 0.3048)
			(end 0.120396 0.2794)
			(stroke
				(width 0.1)
				(type default)
			)
			(layer "F.Fab")
		)
		(fp_line
			(start 0.12065 -0.3048)
			(end 0.67945 -0.3048)
			(stroke
				(width 0.1)
				(type default)
			)
			(layer "F.Fab")
		)
		(fp_line
			(start 0.12065 -0.2794)
			(end 0.12065 -0.3048)
			(stroke
				(width 0.1)
				(type default)
			)
			(layer "F.Fab")
		)
		(fp_line
			(start 0.67945 -0.3048)
			(end 0.67945 0.3048)
			(stroke
				(width 0.1)
				(type default)
			)
			(layer "F.Fab")
		)
		(fp_line
			(start 0.67945 0.3048)
			(end 0.120396 0.3048)
			(stroke
				(width 0.1)
				(type default)
			)
			(layer "F.Fab")
		)
		(pad "1" smd circle
			(at -0.40005 0)
			(size 0 0)
			(layers "F.Cu" "F.Mask" "F.Paste")
			(net "P3V3_PDB_AUX_ADC_MAM")
		)
		(pad "2" smd circle
			(at 0.40005 0)
			(size 0 0)
			(layers "F.Cu" "F.Mask" "F.Paste")
			(net "GND")
		)
	)
)
